(kicad_pcb
	(version 20260206)
	(generator "pcbnew")
	(generator_version "10.0")
	(general
		(thickness 1.6)
		(legacy_teardrops no)
	)
	(paper "A4")
	(title_block
		(title "01162023_DA0F0TEBIF0_F0T_Expander_BD_F_brd_V02_OCP.brd")
		(comment 1 "Grand Teton / footprints 1642-1647 of 9728")
	)
	(layers
		(0 "F.Cu" signal "TOP")
		(4 "In1.Cu" signal "GND")
		(6 "In2.Cu" signal "VCC")
		(8 "In3.Cu" signal "VCC1")
		(10 "In4.Cu" signal "GND1")
		(12 "In5.Cu" signal "IN1")
		(14 "In6.Cu" signal "GND2")
		(16 "In7.Cu" signal "IN2")
		(18 "In8.Cu" signal "GND3")
		(20 "In9.Cu" signal "IN3")
		(22 "In10.Cu" signal "GND4")
		(24 "In11.Cu" signal "IN4")
		(26 "In12.Cu" signal "GND5")
		(28 "In13.Cu" signal "IN5")
		(30 "In14.Cu" signal "GND6")
		(32 "In15.Cu" signal "IN6")
		(34 "In16.Cu" signal "GND7")
		(2 "B.Cu" signal "BOTTOM")
		(9 "F.Adhes" user "F.Adhesive")
		(11 "B.Adhes" user "B.Adhesive")
		(13 "F.Paste" user "Package Geometry/Pastemask Top")
		(15 "B.Paste" user "Package Geometry/Pastemask Bottom")
		(5 "F.SilkS" user "Ref Des/Silkscreen Top")
		(7 "B.SilkS" user "Ref Des/Silkscreen Bottom")
		(1 "F.Mask" user "Board Geometry/Soldermask Top")
		(3 "B.Mask" user "Board Geometry/Soldermask Bottom")
		(17 "Dwgs.User" user "User.Drawings")
		(19 "Cmts.User" user "User.Comments")
		(21 "Eco1.User" user "User.Eco1")
		(23 "Eco2.User" user "User.Eco2")
		(25 "Edge.Cuts" user "Board Geometry/Outline")
		(27 "Margin" user)
		(31 "F.CrtYd" user "Package Geometry/Place Bound Top")
		(29 "B.CrtYd" user "Package Geometry/Place Bound Bottom")
		(35 "F.Fab" user "Ref Des/Assembly Top")
		(33 "B.Fab" user "Ref Des/Assembly Bottom")
	)
	(footprint ""
		(layer "F.Cu")
		(at 227.693474 -136.669272 90)
		(property "Reference" "R4201"
			(at 0 0 90)
			(layer "F.SilkS")
			(hide yes)
			(effects
				(font
					(size 1.27 1.27)
				)
			)
		)
		(property "Value" ""
			(at 0 0 90)
			(layer "F.Fab")
			(effects
				(font
					(size 1.27 1.27)
				)
			)
		)
		(duplicate_pad_numbers_are_jumpers no)
		(fp_line
			(start 0.7874 -0.4064)
			(end 0.7874 0.4064)
			(stroke
				(width 0.1524)
				(type default)
			)
			(layer "F.SilkS")
		)
		(fp_line
			(start -0.7874 -0.4064)
			(end 0.7874 -0.4064)
			(stroke
				(width 0.1524)
				(type default)
			)
			(layer "F.SilkS")
		)
		(fp_line
			(start 0.7874 0.4064)
			(end -0.7874 0.4064)
			(stroke
				(width 0.1524)
				(type default)
			)
			(layer "F.SilkS")
		)
		(fp_line
			(start -0.7874 0.4064)
			(end -0.7874 -0.4064)
			(stroke
				(width 0.1524)
				(type default)
			)
			(layer "F.SilkS")
		)
		(fp_line
			(start -0.12065 -0.305054)
			(end -0.12065 -0.2794)
			(stroke
				(width 0.1)
				(type default)
			)
			(layer "F.Fab")
		)
		(fp_line
			(start -0.67945 -0.305054)
			(end -0.12065 -0.305054)
			(stroke
				(width 0.1)
				(type default)
			)
			(layer "F.Fab")
		)
		(fp_line
			(start 0.67945 -0.3048)
			(end 0.67945 0.3048)
			(stroke
				(width 0.1)
				(type default)
			)
			(layer "F.Fab")
		)
		(fp_line
			(start 0.12065 -0.3048)
			(end 0.67945 -0.3048)
			(stroke
				(width 0.1)
				(type default)
			)
			(layer "F.Fab")
		)
		(fp_line
			(start 0.12065 -0.2794)
			(end 0.12065 -0.3048)
			(stroke
				(width 0.1)
				(type default)
			)
			(layer "F.Fab")
		)
		(fp_line
			(start -0.12065 -0.2794)
			(end 0.12065 -0.2794)
			(stroke
				(width 0.1)
				(type default)
			)
			(layer "F.Fab")
		)
		(fp_line
			(start 0.120396 0.2794)
			(end -0.12065 0.2794)
			(stroke
				(width 0.1)
				(type default)
			)
			(layer "F.Fab")
		)
		(fp_line
			(start -0.12065 0.2794)
			(end -0.12065 0.3048)
			(stroke
				(width 0.1)
				(type default)
			)
			(layer "F.Fab")
		)
		(fp_line
			(start 0.67945 0.3048)
			(end 0.120396 0.3048)
			(stroke
				(width 0.1)
				(type default)
			)
			(layer "F.Fab")
		)
		(fp_line
			(start 0.120396 0.3048)
			(end 0.120396 0.2794)
			(stroke
				(width 0.1)
				(type default)
			)
			(layer "F.Fab")
		)
		(fp_line
			(start -0.12065 0.3048)
			(end -0.67945 0.3048)
			(stroke
				(width 0.1)
				(type default)
			)
			(layer "F.Fab")
		)
		(fp_line
			(start -0.67945 0.3048)
			(end -0.67945 -0.305054)
			(stroke
				(width 0.1)
				(type default)
			)
			(layer "F.Fab")
		)
		(pad "1" smd circle
			(at -0.40005 0 90)
			(size 0 0)
			(layers "F.Cu" "F.Mask" "F.Paste")
			(net "GND")
		)
		(pad "2" smd circle
			(at 0.40005 0 90)
			(size 0 0)
			(layers "F.Cu" "F.Mask" "F.Paste")
			(net "CLK_CK440_PEX_SMB_ADDR1")
		)
	)
	(footprint ""
		(layer "F.Cu")
		(at 13.73124 -125.144784 180)
		(property "Reference" "PU46"
			(at 2.615692 -3.35788 0)
			(unlocked yes)
			(layer "F.SilkS")
			(effects
				(font
					(size 0.7874 0.5842)
					(thickness 0.1524)
				)
				(justify left)
			)
		)
		(property "Value" ""
			(at 0 0 180)
			(layer "F.Fab")
			(effects
				(font
					(size 1.27 1.27)
				)
			)
		)
		(duplicate_pad_numbers_are_jumpers no)
		(fp_line
			(start 1.943608 1.549908)
			(end -1.943608 1.549908)
			(stroke
				(width 0.1524)
				(type default)
			)
			(layer "F.SilkS")
		)
		(fp_line
			(start 1.943608 -1.549908)
			(end 1.943608 1.549908)
			(stroke
				(width 0.1524)
				(type default)
			)
			(layer "F.SilkS")
		)
		(fp_line
			(start -1.943608 1.549908)
			(end -1.943608 -1.549908)
			(stroke
				(width 0.1524)
				(type default)
			)
			(layer "F.SilkS")
		)
		(fp_line
			(start -1.943608 -1.549908)
			(end 1.943608 -1.549908)
			(stroke
				(width 0.1524)
				(type default)
			)
			(layer "F.SilkS")
		)
		(fp_poly
			(pts
				(xy -2.019808 -1.549908) (xy -1.257808 -1.549908) (xy -1.257808 -1.880108) (xy -2.019808 -1.880108)
			)
			(stroke
				(width 0)
				(type default)
			)
			(fill yes)
			(layer "F.SilkS")
		)
		(fp_line
			(start 1.549908 1.549908)
			(end -1.549908 1.549908)
			(stroke
				(width 0.1)
				(type default)
			)
			(layer "F.Fab")
		)
		(fp_line
			(start 1.549908 -1.549908)
			(end 1.549908 1.549908)
			(stroke
				(width 0.1)
				(type default)
			)
			(layer "F.Fab")
		)
		(fp_line
			(start -1.549908 1.549908)
			(end -1.549908 -1.549908)
			(stroke
				(width 0.1)
				(type default)
			)
			(layer "F.Fab")
		)
		(fp_line
			(start -1.549908 -1.549908)
			(end 1.549908 -1.549908)
			(stroke
				(width 0.1)
				(type default)
			)
			(layer "F.Fab")
		)
		(fp_poly
			(pts
				(xy -2.019808 -1.549908) (xy -1.257808 -1.549908) (xy -1.257808 -1.880108) (xy -2.019808 -1.880108)
			)
			(stroke
				(width 0)
				(type default)
			)
			(fill yes)
			(layer "F.Fab")
		)
		(pad "1" smd rect
			(at -1.500124 -1.249934 90)
			(size 0.2794 0.6096)
			(layers "F.Cu" "F.Mask" "F.Paste")
			(net "P3V3_NIC0")
		)
		(pad "2" smd rect
			(at -1.500124 -0.750062 90)
			(size 0.2794 0.6096)
			(layers "F.Cu" "F.Mask" "F.Paste")
			(net "P3V3_NIC0")
		)
		(pad "3" smd rect
			(at -1.500124 -0.249936 90)
			(size 0.2794 0.6096)
			(layers "F.Cu" "F.Mask" "F.Paste")
			(net "P3V3_NIC0")
		)
		(pad "4" smd rect
			(at -1.500124 0.249936 90)
			(size 0.2794 0.6096)
			(layers "F.Cu" "F.Mask" "F.Paste")
			(net "P3V3_NIC0")
		)
		(pad "5" smd rect
			(at -1.500124 0.750062 90)
			(size 0.2794 0.6096)
			(layers "F.Cu" "F.Mask" "F.Paste")
			(net "P3V3_NIC0")
		)
		(pad "6" smd rect
			(at -1.500124 1.249934 90)
			(size 0.2794 0.6096)
			(layers "F.Cu" "F.Mask" "F.Paste")
			(net "GND")
		)
		(pad "7" smd rect
			(at 1.500124 1.249934 90)
			(size 0.2794 0.6096)
			(layers "F.Cu" "F.Mask" "F.Paste")
			(net "P3V3_NIC0_SS")
		)
		(pad "8" smd rect
			(at 1.500124 0.750062 90)
			(size 0.2794 0.6096)
			(layers "F.Cu" "F.Mask" "F.Paste")
			(net "PWRGD_P3V3_NIC0")
		)
		(pad "9" smd rect
			(at 1.500124 0.249936 90)
			(size 0.2794 0.6096)
			(layers "F.Cu" "F.Mask" "F.Paste")
			(net "P3V3_NIC0_OCP")
		)
		(pad "10" smd rect
			(at 1.500124 -0.249936 90)
			(size 0.2794 0.6096)
			(layers "F.Cu" "F.Mask" "F.Paste")
			(net "P5V_AUX")
		)
		(pad "11" smd rect
			(at 1.500124 -0.750062 90)
			(size 0.2794 0.6096)
			(layers "F.Cu" "F.Mask" "F.Paste")
			(net "HP_NIC0_EN")
		)
		(pad "12" smd rect
			(at 1.500124 -1.249934 90)
			(size 0.2794 0.6096)
			(layers "F.Cu" "F.Mask" "F.Paste")
			(net "P3V3_AUX")
		)
		(pad "13" smd rect
			(at 0 0 180)
			(size 1.9812 2.7178)
			(layers "F.Cu" "F.Mask" "F.Paste")
			(net "P3V3_AUX")
		)
		(zone
			(layer "F.Cu")
			(hatch none 0.5)
			(connect_pads
				(clearance 0)
			)
			(min_thickness 0.25)
			(keepout
				(tracks not_allowed)
				(vias allowed)
				(pads allowed)
				(copperpour not_allowed)
				(footprints allowed)
			)
			(placement
				(enabled no)
				(sheetname "")
			)
			(fill
				(thermal_gap 0.5)
				(thermal_bridge_width 0.5)
				(island_removal_mode 0)
			)
			(polygon
				(pts
					(xy 12.58824 -123.595384) (xy 12.58824 -123.722384) (xy 12.58824 -126.694184) (xy 12.58824 -126.694692)
					(xy 14.87424 -126.694692) (xy 14.87424 -126.694184) (xy 14.87424 -126.567184) (xy 14.87424 -125.144784)
					(xy 14.77264 -125.144784) (xy 14.77264 -126.567184) (xy 12.68984 -126.567184) (xy 12.68984 -123.722384)
					(xy 14.77264 -123.722384) (xy 14.77264 -125.119384) (xy 14.87424 -125.119384) (xy 14.87424 -123.722384)
					(xy 14.87424 -123.595384) (xy 14.87424 -123.594876) (xy 12.58824 -123.594876)
				)
			)
		)
	)
	(footprint ""
		(layer "F.Cu")
		(at 271.480534 -106.488738)
		(property "Reference" "C477"
			(at 0 0 0)
			(layer "F.SilkS")
			(hide yes)
			(effects
				(font
					(size 1.27 1.27)
				)
			)
		)
		(property "Value" ""
			(at 0 0 0)
			(layer "F.Fab")
			(effects
				(font
					(size 1.27 1.27)
				)
			)
		)
		(duplicate_pad_numbers_are_jumpers no)
		(fp_line
			(start -0.299974 -0.150114)
			(end 0.299974 -0.150114)
			(stroke
				(width 0.1)
				(type default)
			)
			(layer "F.Fab")
		)
		(fp_line
			(start -0.299974 0.150114)
			(end -0.299974 -0.150114)
			(stroke
				(width 0.1)
				(type default)
			)
			(layer "F.Fab")
		)
		(fp_line
			(start 0.299974 -0.150114)
			(end 0.299974 0.150114)
			(stroke
				(width 0.1)
				(type default)
			)
			(layer "F.Fab")
		)
		(fp_line
			(start 0.299974 0.150114)
			(end -0.299974 0.150114)
			(stroke
				(width 0.1)
				(type default)
			)
			(layer "F.Fab")
		)
		(pad "1" smd rect
			(at -0.2667 0)
			(size 0.3048 0.381)
			(layers "F.Cu" "F.Mask" "F.Paste")
			(net "P5E_PEX2_STN1_TX_DP<20>")
		)
		(pad "2" smd rect
			(at 0.2667 0)
			(size 0.3048 0.381)
			(layers "F.Cu" "F.Mask" "F.Paste")
			(net "P5E_PEX2_STN1_TX_C_DP<20>")
		)
	)
	(footprint ""
		(layer "F.Cu")
		(at 375.76252 -22.937216 90)
		(property "Reference" "R1725"
			(at 0 0 90)
			(layer "F.SilkS")
			(hide yes)
			(effects
				(font
					(size 1.27 1.27)
				)
			)
		)
		(property "Value" ""
			(at 0 0 90)
			(layer "F.Fab")
			(effects
				(font
					(size 1.27 1.27)
				)
			)
		)
		(duplicate_pad_numbers_are_jumpers no)
		(fp_line
			(start 0.7874 -0.4064)
			(end 0.7874 0.4064)
			(stroke
				(width 0.1524)
				(type default)
			)
			(layer "F.SilkS")
		)
		(fp_line
			(start -0.7874 -0.4064)
			(end 0.7874 -0.4064)
			(stroke
				(width 0.1524)
				(type default)
			)
			(layer "F.SilkS")
		)
		(fp_line
			(start 0.7874 0.4064)
			(end -0.7874 0.4064)
			(stroke
				(width 0.1524)
				(type default)
			)
			(layer "F.SilkS")
		)
		(fp_line
			(start -0.7874 0.4064)
			(end -0.7874 -0.4064)
			(stroke
				(width 0.1524)
				(type default)
			)
			(layer "F.SilkS")
		)
		(fp_line
			(start -0.12065 -0.305054)
			(end -0.12065 -0.2794)
			(stroke
				(width 0.1)
				(type default)
			)
			(layer "F.Fab")
		)
		(fp_line
			(start -0.67945 -0.305054)
			(end -0.12065 -0.305054)
			(stroke
				(width 0.1)
				(type default)
			)
			(layer "F.Fab")
		)
		(fp_line
			(start 0.67945 -0.3048)
			(end 0.67945 0.3048)
			(stroke
				(width 0.1)
				(type default)
			)
			(layer "F.Fab")
		)
		(fp_line
			(start 0.12065 -0.3048)
			(end 0.67945 -0.3048)
			(stroke
				(width 0.1)
				(type default)
			)
			(layer "F.Fab")
		)
		(fp_line
			(start 0.12065 -0.2794)
			(end 0.12065 -0.3048)
			(stroke
				(width 0.1)
				(type default)
			)
			(layer "F.Fab")
		)
		(fp_line
			(start -0.12065 -0.2794)
			(end 0.12065 -0.2794)
			(stroke
				(width 0.1)
				(type default)
			)
			(layer "F.Fab")
		)
		(fp_line
			(start 0.120396 0.2794)
			(end -0.12065 0.2794)
			(stroke
				(width 0.1)
				(type default)
			)
			(layer "F.Fab")
		)
		(fp_line
			(start -0.12065 0.2794)
			(end -0.12065 0.3048)
			(stroke
				(width 0.1)
				(type default)
			)
			(layer "F.Fab")
		)
		(fp_line
			(start 0.67945 0.3048)
			(end 0.120396 0.3048)
			(stroke
				(width 0.1)
				(type default)
			)
			(layer "F.Fab")
		)
		(fp_line
			(start 0.120396 0.3048)
			(end 0.120396 0.2794)
			(stroke
				(width 0.1)
				(type default)
			)
			(layer "F.Fab")
		)
		(fp_line
			(start -0.12065 0.3048)
			(end -0.67945 0.3048)
			(stroke
				(width 0.1)
				(type default)
			)
			(layer "F.Fab")
		)
		(fp_line
			(start -0.67945 0.3048)
			(end -0.67945 -0.305054)
			(stroke
				(width 0.1)
				(type default)
			)
			(layer "F.Fab")
		)
		(pad "1" smd circle
			(at -0.40005 0 90)
			(size 0 0)
			(layers "F.Cu" "F.Mask" "F.Paste")
			(net "SMB_BIC_I2C9_MUX1_SSD12_R_SDA")
		)
		(pad "2" smd circle
			(at 0.40005 0 90)
			(size 0 0)
			(layers "F.Cu" "F.Mask" "F.Paste")
			(net "SMB_ISO_SSD12_SDA")
		)
	)
	(footprint ""
		(layer "F.Cu")
		(at 241.075464 -217.78976)
		(property "Reference" "C3614"
			(at 0 0 0)
			(layer "F.SilkS")
			(hide yes)
			(effects
				(font
					(size 1.27 1.27)
				)
			)
		)
		(property "Value" ""
			(at 0 0 0)
			(layer "F.Fab")
			(effects
				(font
					(size 1.27 1.27)
				)
			)
		)
		(duplicate_pad_numbers_are_jumpers no)
		(fp_line
			(start -0.69215 -0.2921)
			(end 0.69215 -0.2921)
			(stroke
				(width 0.1524)
				(type default)
			)
			(layer "F.SilkS")
		)
		(fp_line
			(start -0.69215 0.2921)
			(end -0.69215 -0.2921)
			(stroke
				(width 0.1524)
				(type default)
			)
			(layer "F.SilkS")
		)
		(fp_line
			(start 0.69215 -0.2921)
			(end 0.69215 0.2921)
			(stroke
				(width 0.1524)
				(type default)
			)
			(layer "F.SilkS")
		)
		(fp_line
			(start 0.69215 0.2921)
			(end -0.69215 0.2921)
			(stroke
				(width 0.1524)
				(type default)
			)
			(layer "F.SilkS")
		)
		(fp_line
			(start -0.51435 -0.2794)
			(end 0.51435 -0.2794)
			(stroke
				(width 0.1)
				(type default)
			)
			(layer "F.Fab")
		)
		(fp_line
			(start -0.51435 0.2794)
			(end -0.51435 -0.2794)
			(stroke
				(width 0.1)
				(type default)
			)
			(layer "F.Fab")
		)
		(fp_line
			(start 0.51435 -0.2794)
			(end 0.51435 0.2794)
			(stroke
				(width 0.1)
				(type default)
			)
			(layer "F.Fab")
		)
		(fp_line
			(start 0.51435 0.2794)
			(end -0.51435 0.2794)
			(stroke
				(width 0.1)
				(type default)
			)
			(layer "F.Fab")
		)
		(pad "1" smd circle
			(at -0.40005 0)
			(size 0 0)
			(layers "F.Cu" "F.Mask" "F.Paste")
			(net "BIC_ADCVREFP0")
		)
		(pad "2" smd circle
			(at 0.40005 0)
			(size 0 0)
			(layers "F.Cu" "F.Mask" "F.Paste")
			(net "GND")
		)
		(zone
			(layer "F.Cu")
			(hatch none 0.5)
			(connect_pads
				(clearance 0)
			)
			(min_thickness 0.25)
			(keepout
				(tracks not_allowed)
				(vias allowed)
				(pads allowed)
				(copperpour not_allowed)
				(footprints allowed)
			)
			(placement
				(enabled no)
				(sheetname "")
			)
			(fill
				(thermal_gap 0.5)
				(thermal_bridge_width 0.5)
				(island_removal_mode 0)
			)
			(polygon
				(pts
					(xy 240.884964 -217.70213) (xy 240.976404 -217.643964) (xy 241.175794 -217.643964) (xy 241.265964 -217.70213)
					(xy 241.265964 -217.87739) (xy 241.175794 -217.93581) (xy 240.976404 -217.93581) (xy 240.884964 -217.877644)
				)
			)
		)
	)
	(footprint ""
		(layer "F.Cu")
		(at 368.9731 -22.867366 90)
		(property "Reference" "C3956"
			(at 0 0 90)
			(layer "F.SilkS")
			(hide yes)
			(effects
				(font
					(size 1.27 1.27)
				)
			)
		)
		(property "Value" ""
			(at 0 0 90)
			(layer "F.Fab")
			(effects
				(font
					(size 1.27 1.27)
				)
			)
		)
		(duplicate_pad_numbers_are_jumpers no)
		(fp_line
			(start 0.7874 -0.4064)
			(end 0.7874 0.4064)
			(stroke
				(width 0.1524)
				(type default)
			)
			(layer "F.SilkS")
		)
		(fp_line
			(start -0.7874 -0.4064)
			(end 0.7874 -0.4064)
			(stroke
				(width 0.1524)
				(type default)
			)
			(layer "F.SilkS")
		)
		(fp_line
			(start 0.7874 0.4064)
			(end -0.7874 0.4064)
			(stroke
				(width 0.1524)
				(type default)
			)
			(layer "F.SilkS")
		)
		(fp_line
			(start -0.7874 0.4064)
			(end -0.7874 -0.4064)
			(stroke
				(width 0.1524)
				(type default)
			)
			(layer "F.SilkS")
		)
		(fp_line
			(start -0.12065 -0.305054)
			(end -0.12065 -0.2794)
			(stroke
				(width 0.1)
				(type default)
			)
			(layer "F.Fab")
		)
		(fp_line
			(start -0.67945 -0.305054)
			(end -0.12065 -0.305054)
			(stroke
				(width 0.1)
				(type default)
			)
			(layer "F.Fab")
		)
		(fp_line
			(start 0.67945 -0.3048)
			(end 0.67945 0.3048)
			(stroke
				(width 0.1)
				(type default)
			)
			(layer "F.Fab")
		)
		(fp_line
			(start 0.12065 -0.3048)
			(end 0.67945 -0.3048)
			(stroke
				(width 0.1)
				(type default)
			)
			(layer "F.Fab")
		)
		(fp_line
			(start 0.12065 -0.2794)
			(end 0.12065 -0.3048)
			(stroke
				(width 0.1)
				(type default)
			)
			(layer "F.Fab")
		)
		(fp_line
			(start -0.12065 -0.2794)
			(end 0.12065 -0.2794)
			(stroke
				(width 0.1)
				(type default)
			)
			(layer "F.Fab")
		)
		(fp_line
			(start 0.120396 0.2794)
			(end -0.12065 0.2794)
			(stroke
				(width 0.1)
				(type default)
			)
			(layer "F.Fab")
		)
		(fp_line
			(start -0.12065 0.2794)
			(end -0.12065 0.3048)
			(stroke
				(width 0.1)
				(type default)
			)
			(layer "F.Fab")
		)
		(fp_line
			(start 0.67945 0.3048)
			(end 0.120396 0.3048)
			(stroke
				(width 0.1)
				(type default)
			)
			(layer "F.Fab")
		)
		(fp_line
			(start 0.120396 0.3048)
			(end 0.120396 0.2794)
			(stroke
				(width 0.1)
				(type default)
			)
			(layer "F.Fab")
		)
		(fp_line
			(start -0.12065 0.3048)
			(end -0.67945 0.3048)
			(stroke
				(width 0.1)
				(type default)
			)
			(layer "F.Fab")
		)
		(fp_line
			(start -0.67945 0.3048)
			(end -0.67945 -0.305054)
			(stroke
				(width 0.1)
				(type default)
			)
			(layer "F.Fab")
		)
		(pad "1" smd circle
			(at -0.40005 0 90)
			(size 0 0)
			(layers "F.Cu" "F.Mask" "F.Paste")
			(net "P12V_SSD12")
		)
		(pad "2" smd circle
			(at 0.40005 0 90)
			(size 0 0)
			(layers "F.Cu" "F.Mask" "F.Paste")
			(net "GND")
		)
	)
)
